FILE_TYPE = MACRO_DRAWING;
SET COLOR_WIRE YELLOW;
SET COLOR_PROP MONO;
SET COLOR_DOT WHITE;
SET COLOR_ARC YELLOW;
SET COLOR_BODY GREEN;
SET COLOR_NOTE MONO;
SET PROP_DISPLAY VALUE;
SET PAGE_NUMBER P128;
FORCEADD INTEL_CORP_BPAGE..1
(10400 700);
FORCEPROP 1 LAST CDS_CON_LAST_MODIFIED Fri Jun 16 17:48:49 2017
J 0
(8975 1025);
DISPLAY 1.361702 (8975 1025);
PAINT ORANGE (8975 1025);
DISPLAY INVISIBLE (8975 1025);
FORCEPROP 1 LAST CUSTOM_TXT_CDS <CURRENT_DESIGN_SHEET> OF <TOTAL_DESIGN_SHEETS>
J 0
(9900 725);
PAINT ORANGE (9900 725);
FORCEPROP 2 LAST CUSTOM_TXT_CDS <XR_PAGE_TITLE>
J 0
(2510 5950);
DISPLAY 0.638298 (2510 5950);
PAINT PINK (2510 5950);
DISPLAY INVISIBLE (2510 5950);
FORCEPROP 2 LAST CUSTOM_TXT_CDS <CON_LAST_MODIFIED>
J 0
(6400 800);
DISPLAY 1.085106 (6400 800);
PAINT ORANGE (6400 800);
FORCEPROP 1 LAST SCH_TITLE SPARE
J 0
(2450 750);
DISPLAY 1.212766 (2450 750);
PAINT ORANGE (2450 750);
FORCEPROP 2 LAST PAGE_BORDER TRUE
J 0
(2510 5950);
DISPLAY 0.851064 (2510 5950);
PAINT PINK (2510 5950);
DISPLAY INVISIBLE (2510 5950);
FORCEPROP 2 LAST CDS_LIB mstr_symbols
J 0
(10400 700);
DISPLAY 1.361702 (10400 700);
PAINT MONO (10400 700);
DISPLAY INVISIBLE (10400 700);
FORCEPROP 1 LAST COMMENT_BODY TRUE
J 0
(10412 712);
DISPLAY 0.617021 (10412 712);
PAINT GREEN (10412 712);
DISPLAY INVISIBLE (10412 712);
FORCEPROP 2 LAST CDS_XR_PAGE_TITLE CR-128 : @BASEBOARD_FAB2_LIB.BASEBOARD_FAB2(SCH_1):PAGE128
J 0
(2510 5950);
DISPLAY 0.638298 (2510 5950);
PAINT PINK (2510 5950);
DISPLAY INVISIBLE (2510 5950);
QUIT
